# T6G (Grand Teton) — schematic parts with pin connectivity, parts 689–806 of 8303; source: Cadence DE-HDL packaged netlist (pstxprt.dat, pstxnet.dat, pstchip.dat)

C688  Q_CAP_DIFFBUS  DIFF BUS_0.22UF 6.3V 20% X6S  pkg C0201  page 67 : 1 = P5E_CPU1_G1_TX_C_DN<10> ; 2 = P5E_CPU1_G1_TX_DN<10>
C689  Q_CAP_DIFFBUS  DIFF BUS_0.22UF 6.3V 20% X6S  pkg C0201  page 67 : 1 = P5E_CPU1_G1_TX_C_DP<10> ; 2 = P5E_CPU1_G1_TX_DP<10>
C690  Q_CAP_DIFFBUS  DIFF BUS_0.22UF 6.3V 20% X6S  pkg C0201  page 67 : 1 = P5E_CPU1_G1_TX_C_DN<9> ; 2 = P5E_CPU1_G1_TX_DN<9>
C691  Q_CAP_DIFFBUS  DIFF BUS_0.22UF 6.3V 20% X6S  pkg C0201  page 67 : 1 = P5E_CPU1_G1_TX_C_DP<9> ; 2 = P5E_CPU1_G1_TX_DP<9>
C692  Q_CAP_DIFFBUS  DIFF BUS_0.22UF 6.3V 20% X6S  pkg C0201  page 67 : 1 = P5E_CPU1_G1_TX_C_DN<8> ; 2 = P5E_CPU1_G1_TX_DN<8>
C693  Q_CAP  0.1UF 25V 10% X7R  pkg 0402  page 167 : 1 = U124_VCC ; 2 = GND
C694  Q_CAP_DIFFBUS  DIFF BUS_0.22UF 6.3V 20% X6S  pkg C0201  page 67 : 1 = P5E_CPU1_G1_TX_C_DN<7> ; 2 = P5E_CPU1_G1_TX_DN<7>
C695  Q_CAP_DIFFBUS  DIFF BUS_0.22UF 6.3V 20% X6S  pkg C0201  page 67 : 1 = P5E_CPU1_G1_TX_C_DP<7> ; 2 = P5E_CPU1_G1_TX_DP<7>
C696  Q_CAP_DIFFBUS  DIFF BUS_0.22UF 6.3V 20% X6S  pkg C0201  page 67 : 1 = P5E_CPU1_G1_TX_C_DN<6> ; 2 = P5E_CPU1_G1_TX_DN<6>
C697  Q_CAP_DIFFBUS  DIFF BUS_0.22UF 6.3V 20% X6S  pkg C0201  page 67 : 1 = P5E_CPU1_G1_TX_C_DP<6> ; 2 = P5E_CPU1_G1_TX_DP<6>
C698  Q_CAP_DIFFBUS  DIFF BUS_0.22UF 6.3V 20% X6S  pkg C0201  page 67 : 1 = P5E_CPU1_G1_TX_C_DN<5> ; 2 = P5E_CPU1_G1_TX_DN<5>
C699  Q_CAP_DIFFBUS  DIFF BUS_0.22UF 6.3V 20% X6S  pkg C0201  page 67 : 1 = P5E_CPU1_G1_TX_C_DP<5> ; 2 = P5E_CPU1_G1_TX_DP<5>
C700  Q_CAP_DIFFBUS  DIFF BUS_0.22UF 6.3V 20% X6S  pkg C0201  page 67 : 1 = P5E_CPU1_G1_TX_C_DN<4> ; 2 = P5E_CPU1_G1_TX_DN<4>
C701  Q_CAP_DIFFBUS  DIFF BUS_0.22UF 6.3V 20% X6S  pkg C0201  page 67 : 1 = P5E_CPU1_G1_TX_C_DP<4> ; 2 = P5E_CPU1_G1_TX_DP<4>
C702  Q_CAP_DIFFBUS  DIFF BUS_0.22UF 6.3V 20% X6S  pkg C0201  page 67 : 1 = P5E_CPU1_G1_TX_C_DN<3> ; 2 = P5E_CPU1_G1_TX_DN<3>
C703  Q_CAP_DIFFBUS  DIFF BUS_0.22UF 6.3V 20% X6S  pkg C0201  page 67 : 1 = P5E_CPU1_G1_TX_C_DP<3> ; 2 = P5E_CPU1_G1_TX_DP<3>
C704  Q_CAP_DIFFBUS  DIFF BUS_0.22UF 6.3V 20% X6S  pkg C0201  page 67 : 1 = P5E_CPU1_G1_TX_C_DN<2> ; 2 = P5E_CPU1_G1_TX_DN<2>
C705  Q_CAP_DIFFBUS  DIFF BUS_0.22UF 6.3V 20% X6S  pkg C0201  page 67 : 1 = P5E_CPU1_G1_TX_C_DP<2> ; 2 = P5E_CPU1_G1_TX_DP<2>
C706  Q_CAP_DIFFBUS  DIFF BUS_0.22UF 6.3V 20% X6S  pkg C0201  page 67 : 1 = P5E_CPU1_G1_TX_C_DN<1> ; 2 = P5E_CPU1_G1_TX_DN<1>
C707  Q_CAP_DIFFBUS  DIFF BUS_0.22UF 6.3V 20% X6S  pkg C0201  page 67 : 1 = P5E_CPU1_G1_TX_C_DP<1> ; 2 = P5E_CPU1_G1_TX_DP<1>
C708  Q_CAP_DIFFBUS  DIFF BUS_0.22UF 6.3V 20% X6S  pkg C0201  page 67 : 1 = P5E_CPU1_G1_TX_C_DN<0> ; 2 = P5E_CPU1_G1_TX_DN<0>
C709  Q_CAP_DIFFBUS  DIFF BUS_0.22UF 6.3V 20% X6S  pkg C0201  page 67 : 1 = P5E_CPU1_G1_TX_C_DP<0> ; 2 = P5E_CPU1_G1_TX_DP<0>
C710  Q_CAP_DIFFBUS  DIFF BUS_0.22UF 6.3V 20% X6S  pkg C0201  page 66 : 1 = P5E_CPU1_P1_TX_C_DN<15> ; 2 = P5E_CPU1_P1_TX_DN<15>
C711  Q_CAP_DIFFBUS  DIFF BUS_0.22UF 6.3V 20% X6S  pkg C0201  page 66 : 1 = P5E_CPU1_P1_TX_C_DP<15> ; 2 = P5E_CPU1_P1_TX_DP<15>
C712  Q_CAP_DIFFBUS  DIFF BUS_0.22UF 6.3V 20% X6S  pkg C0201  page 66 : 1 = P5E_CPU1_P1_TX_C_DN<14> ; 2 = P5E_CPU1_P1_TX_DN<14>
C713  Q_CAP_DIFFBUS  DIFF BUS_0.22UF 6.3V 20% X6S  pkg C0201  page 66 : 1 = P5E_CPU1_P1_TX_C_DP<14> ; 2 = P5E_CPU1_P1_TX_DP<14>
C714  Q_CAP_DIFFBUS  DIFF BUS_0.22UF 6.3V 20% X6S  pkg C0201  page 66 : 1 = P5E_CPU1_P1_TX_C_DN<13> ; 2 = P5E_CPU1_P1_TX_DN<13>
C715  Q_CAP_DIFFBUS  DIFF BUS_0.22UF 6.3V 20% X6S  pkg C0201  page 66 : 1 = P5E_CPU1_P1_TX_C_DP<13> ; 2 = P5E_CPU1_P1_TX_DP<13>
C716  Q_CAP_DIFFBUS  DIFF BUS_0.22UF 6.3V 20% X6S  pkg C0201  page 66 : 1 = P5E_CPU1_P1_TX_C_DN<12> ; 2 = P5E_CPU1_P1_TX_DN<12>
C717  Q_CAP_DIFFBUS  DIFF BUS_0.22UF 6.3V 20% X6S  pkg C0201  page 66 : 1 = P5E_CPU1_P1_TX_C_DP<12> ; 2 = P5E_CPU1_P1_TX_DP<12>
C718  Q_CAP_DIFFBUS  DIFF BUS_0.22UF 6.3V 20% X6S  pkg C0201  page 66 : 1 = P5E_CPU1_P1_TX_C_DN<11> ; 2 = P5E_CPU1_P1_TX_DN<11>
C719  Q_CAP_DIFFBUS  DIFF BUS_0.22UF 6.3V 20% X6S  pkg C0201  page 66 : 1 = P5E_CPU1_P1_TX_C_DP<11> ; 2 = P5E_CPU1_P1_TX_DP<11>
C720  Q_CAP_DIFFBUS  DIFF BUS_0.22UF 6.3V 20% X6S  pkg C0201  page 66 : 1 = P5E_CPU1_P1_TX_C_DN<10> ; 2 = P5E_CPU1_P1_TX_DN<10>
C721  Q_CAP_DIFFBUS  DIFF BUS_0.22UF 6.3V 20% X6S  pkg C0201  page 66 : 1 = P5E_CPU1_P1_TX_C_DP<10> ; 2 = P5E_CPU1_P1_TX_DP<10>
C722  Q_CAP_DIFFBUS  DIFF BUS_0.22UF 6.3V 20% X6S  pkg C0201  page 66 : 1 = P5E_CPU1_P1_TX_C_DN<9> ; 2 = P5E_CPU1_P1_TX_DN<9>
C723  Q_CAP_DIFFBUS  DIFF BUS_0.22UF 6.3V 20% X6S  pkg C0201  page 66 : 1 = P5E_CPU1_P1_TX_C_DP<9> ; 2 = P5E_CPU1_P1_TX_DP<9>
C724  Q_CAP_DIFFBUS  DIFF BUS_0.22UF 6.3V 20% X6S  pkg C0201  page 66 : 1 = P5E_CPU1_P1_TX_C_DN<8> ; 2 = P5E_CPU1_P1_TX_DN<8>
C725  Q_CAP_DIFFBUS  DIFF BUS_0.22UF 6.3V 20% X6S  pkg C0201  page 66 : 1 = P5E_CPU1_P1_TX_C_DP<8> ; 2 = P5E_CPU1_P1_TX_DP<8>
C726  Q_CAP_DIFFBUS  DIFF BUS_0.22UF 6.3V 20% X6S  pkg C0201  page 66 : 1 = P5E_CPU1_P1_TX_C_DN<7> ; 2 = P5E_CPU1_P1_TX_DN<7>
C727  Q_CAP_DIFFBUS  DIFF BUS_0.22UF 6.3V 20% X6S  pkg C0201  page 66 : 1 = P5E_CPU1_P1_TX_C_DP<7> ; 2 = P5E_CPU1_P1_TX_DP<7>
C728  Q_CAP_DIFFBUS  DIFF BUS_0.22UF 6.3V 20% X6S  pkg C0201  page 66 : 1 = P5E_CPU1_P1_TX_C_DN<6> ; 2 = P5E_CPU1_P1_TX_DN<6>
C729  Q_CAP_DIFFBUS  DIFF BUS_0.22UF 6.3V 20% X6S  pkg C0201  page 66 : 1 = P5E_CPU1_P1_TX_C_DP<6> ; 2 = P5E_CPU1_P1_TX_DP<6>
C730  Q_CAP_DIFFBUS  DIFF BUS_0.22UF 6.3V 20% X6S  pkg C0201  page 66 : 1 = P5E_CPU1_P1_TX_C_DN<5> ; 2 = P5E_CPU1_P1_TX_DN<5>
C731  Q_CAP_DIFFBUS  DIFF BUS_0.22UF 6.3V 20% X6S  pkg C0201  page 66 : 1 = P5E_CPU1_P1_TX_C_DP<5> ; 2 = P5E_CPU1_P1_TX_DP<5>
C732  Q_CAP_DIFFBUS  DIFF BUS_0.22UF 6.3V 20% X6S  pkg C0201  page 66 : 1 = P5E_CPU1_P1_TX_C_DN<4> ; 2 = P5E_CPU1_P1_TX_DN<4>
C733  Q_CAP_DIFFBUS  DIFF BUS_0.22UF 6.3V 20% X6S  pkg C0201  page 66 : 1 = P5E_CPU1_P1_TX_C_DP<4> ; 2 = P5E_CPU1_P1_TX_DP<4>
C734  Q_CAP_DIFFBUS  DIFF BUS_0.22UF 6.3V 20% X6S  pkg C0201  page 66 : 1 = P5E_CPU1_P1_TX_C_DN<3> ; 2 = P5E_CPU1_P1_TX_DN<3>
C735  Q_CAP_DIFFBUS  DIFF BUS_0.22UF 6.3V 20% X6S  pkg C0201  page 66 : 1 = P5E_CPU1_P1_TX_C_DP<3> ; 2 = P5E_CPU1_P1_TX_DP<3>
C736  Q_CAP_DIFFBUS  DIFF BUS_0.22UF 6.3V 20% X6S  pkg C0201  page 66 : 1 = P5E_CPU1_P1_TX_C_DN<2> ; 2 = P5E_CPU1_P1_TX_DN<2>
C737  Q_CAP_DIFFBUS  DIFF BUS_0.22UF 6.3V 20% X6S  pkg C0201  page 66 : 1 = P5E_CPU1_P1_TX_C_DP<2> ; 2 = P5E_CPU1_P1_TX_DP<2>
C738  Q_CAP_DIFFBUS  DIFF BUS_0.22UF 6.3V 20% X6S  pkg C0201  page 66 : 1 = P5E_CPU1_P1_TX_C_DN<1> ; 2 = P5E_CPU1_P1_TX_DN<1>
C739  Q_CAP_DIFFBUS  DIFF BUS_0.22UF 6.3V 20% X6S  pkg C0201  page 66 : 1 = P5E_CPU1_P1_TX_C_DP<1> ; 2 = P5E_CPU1_P1_TX_DP<1>
C740  Q_CAP_DIFFBUS  DIFF BUS_0.22UF 6.3V 20% X6S  pkg C0201  page 66 : 1 = P5E_CPU1_P1_TX_C_DN<0> ; 2 = P5E_CPU1_P1_TX_DN<0>
C741  Q_CAP_DIFFBUS  DIFF BUS_0.22UF 6.3V 20% X6S  pkg C0201  page 66 : 1 = P5E_CPU1_P1_TX_C_DP<0> ; 2 = P5E_CPU1_P1_TX_DP<0>
C742  Q_CAP_DIFFBUS  DIFF BUS_0.22UF 6.3V 20% X6S  pkg C0201  page 66 : 1 = P5E_CPU1_P2_TX_C_DN<15> ; 2 = P5E_CPU1_P2_TX_DN<15>
C743  Q_CAP_DIFFBUS  DIFF BUS_0.22UF 6.3V 20% X6S  pkg C0201  page 66 : 1 = P5E_CPU1_P2_TX_C_DP<15> ; 2 = P5E_CPU1_P2_TX_DP<15>
C744  Q_CAP_DIFFBUS  DIFF BUS_0.22UF 6.3V 20% X6S  pkg C0201  page 66 : 1 = P5E_CPU1_P2_TX_C_DN<14> ; 2 = P5E_CPU1_P2_TX_DN<14>
C745  Q_CAP_DIFFBUS  DIFF BUS_0.22UF 6.3V 20% X6S  pkg C0201  page 66 : 1 = P5E_CPU1_P2_TX_C_DP<14> ; 2 = P5E_CPU1_P2_TX_DP<14>
C746  Q_CAP_DIFFBUS  DIFF BUS_0.22UF 6.3V 20% X6S  pkg C0201  page 66 : 1 = P5E_CPU1_P2_TX_C_DN<13> ; 2 = P5E_CPU1_P2_TX_DN<13>
C747  Q_CAP_DIFFBUS  DIFF BUS_0.22UF 6.3V 20% X6S  pkg C0201  page 66 : 1 = P5E_CPU1_P2_TX_C_DP<13> ; 2 = P5E_CPU1_P2_TX_DP<13>
C748  Q_CAP_DIFFBUS  DIFF BUS_0.22UF 6.3V 20% X6S  pkg C0201  page 66 : 1 = P5E_CPU1_P2_TX_C_DN<12> ; 2 = P5E_CPU1_P2_TX_DN<12>
C749  Q_CAP_DIFFBUS  DIFF BUS_0.22UF 6.3V 20% X6S  pkg C0201  page 66 : 1 = P5E_CPU1_P2_TX_C_DP<12> ; 2 = P5E_CPU1_P2_TX_DP<12>
C750  Q_CAP_DIFFBUS  DIFF BUS_0.22UF 6.3V 20% X6S  pkg C0201  page 66 : 1 = P5E_CPU1_P2_TX_C_DN<11> ; 2 = P5E_CPU1_P2_TX_DN<11>
C751  Q_CAP_DIFFBUS  DIFF BUS_0.22UF 6.3V 20% X6S  pkg C0201  page 66 : 1 = P5E_CPU1_P2_TX_C_DP<11> ; 2 = P5E_CPU1_P2_TX_DP<11>
C752  Q_CAP_DIFFBUS  DIFF BUS_0.22UF 6.3V 20% X6S  pkg C0201  page 66 : 1 = P5E_CPU1_P2_TX_C_DN<10> ; 2 = P5E_CPU1_P2_TX_DN<10>
C753  Q_CAP_DIFFBUS  DIFF BUS_0.22UF 6.3V 20% X6S  pkg C0201  page 66 : 1 = P5E_CPU1_P2_TX_C_DP<10> ; 2 = P5E_CPU1_P2_TX_DP<10>
C754  Q_CAP_DIFFBUS  DIFF BUS_0.22UF 6.3V 20% X6S  pkg C0201  page 66 : 1 = P5E_CPU1_P2_TX_C_DN<9> ; 2 = P5E_CPU1_P2_TX_DN<9>
C755  Q_CAP_DIFFBUS  DIFF BUS_0.22UF 6.3V 20% X6S  pkg C0201  page 66 : 1 = P5E_CPU1_P2_TX_C_DP<9> ; 2 = P5E_CPU1_P2_TX_DP<9>
C756  Q_CAP_DIFFBUS  DIFF BUS_0.22UF 6.3V 20% X6S  pkg C0201  page 66 : 1 = P5E_CPU1_P2_TX_C_DN<8> ; 2 = P5E_CPU1_P2_TX_DN<8>
C757  Q_CAP_DIFFBUS  DIFF BUS_0.22UF 6.3V 20% X6S  pkg C0201  page 66 : 1 = P5E_CPU1_P2_TX_C_DP<8> ; 2 = P5E_CPU1_P2_TX_DP<8>
C758  Q_CAP_DIFFBUS  DIFF BUS_0.22UF 6.3V 20% X6S  pkg C0201  page 66 : 1 = P5E_CPU1_P2_TX_C_DN<7> ; 2 = P5E_CPU1_P2_TX_DN<7>
C759  Q_CAP_DIFFBUS  DIFF BUS_0.22UF 6.3V 20% X6S  pkg C0201  page 66 : 1 = P5E_CPU1_P2_TX_C_DP<7> ; 2 = P5E_CPU1_P2_TX_DP<7>
C760  Q_CAP_DIFFBUS  DIFF BUS_0.22UF 6.3V 20% X6S  pkg C0201  page 66 : 1 = P5E_CPU1_P2_TX_C_DN<6> ; 2 = P5E_CPU1_P2_TX_DN<6>
C761  Q_CAP_DIFFBUS  DIFF BUS_0.22UF 6.3V 20% X6S  pkg C0201  page 66 : 1 = P5E_CPU1_P2_TX_C_DP<6> ; 2 = P5E_CPU1_P2_TX_DP<6>
C762  Q_CAP_DIFFBUS  DIFF BUS_0.22UF 6.3V 20% X6S  pkg C0201  page 66 : 1 = P5E_CPU1_P2_TX_C_DN<5> ; 2 = P5E_CPU1_P2_TX_DN<5>
C763  Q_CAP_DIFFBUS  DIFF BUS_0.22UF 6.3V 20% X6S  pkg C0201  page 66 : 1 = P5E_CPU1_P2_TX_C_DP<5> ; 2 = P5E_CPU1_P2_TX_DP<5>
C764  Q_CAP_DIFFBUS  DIFF BUS_0.22UF 6.3V 20% X6S  pkg C0201  page 66 : 1 = P5E_CPU1_P2_TX_C_DN<4> ; 2 = P5E_CPU1_P2_TX_DN<4>
C765  Q_CAP_DIFFBUS  DIFF BUS_0.22UF 6.3V 20% X6S  pkg C0201  page 66 : 1 = P5E_CPU1_P2_TX_C_DP<4> ; 2 = P5E_CPU1_P2_TX_DP<4>
C766  Q_CAP_DIFFBUS  DIFF BUS_0.22UF 6.3V 20% X6S  pkg C0201  page 66 : 1 = P5E_CPU1_P2_TX_C_DN<3> ; 2 = P5E_CPU1_P2_TX_DN<3>
C767  Q_CAP_DIFFBUS  DIFF BUS_0.22UF 6.3V 20% X6S  pkg C0201  page 66 : 1 = P5E_CPU1_P2_TX_C_DP<3> ; 2 = P5E_CPU1_P2_TX_DP<3>
C768  Q_CAP_DIFFBUS  DIFF BUS_0.22UF 6.3V 20% X6S  pkg C0201  page 66 : 1 = P5E_CPU1_P2_TX_C_DN<2> ; 2 = P5E_CPU1_P2_TX_DN<2>
C769  Q_CAP_DIFFBUS  DIFF BUS_0.22UF 6.3V 20% X6S  pkg C0201  page 66 : 1 = P5E_CPU1_P2_TX_C_DP<2> ; 2 = P5E_CPU1_P2_TX_DP<2>
C770  Q_CAP_DIFFBUS  DIFF BUS_0.22UF 6.3V 20% X6S  pkg C0201  page 66 : 1 = P5E_CPU1_P2_TX_C_DN<1> ; 2 = P5E_CPU1_P2_TX_DN<1>
C771  Q_CAP_DIFFBUS  DIFF BUS_0.22UF 6.3V 20% X6S  pkg C0201  page 66 : 1 = P5E_CPU1_P2_TX_C_DP<1> ; 2 = P5E_CPU1_P2_TX_DP<1>
C772  Q_CAP_DIFFBUS  DIFF BUS_0.22UF 6.3V 20% X6S  pkg C0201  page 66 : 1 = P5E_CPU1_P2_TX_C_DN<0> ; 2 = P5E_CPU1_P2_TX_DN<0>
C773  Q_CAP_DIFFBUS  DIFF BUS_0.22UF 6.3V 20% X6S  pkg C0201  page 66 : 1 = P5E_CPU1_P2_TX_C_DP<0> ; 2 = P5E_CPU1_P2_TX_DP<0>
C774  Q_CAP  0.1UF 10V 10% X7S  pkg C0201  page 301 : 1 = P1V8_CPU0_RT2_1A ; 2 = GND
C775  Q_CAP  0.1UF 10V 10% X7S  pkg C0201  page 301 : 1 = P1V8_CPU0_RT2_1A_1D ; 2 = GND
C776  Q_CAP  0.1UF 10V 10% X7S  pkg C0201  page 301 : 1 = P1V8_CPU0_RT2_1A ; 2 = GND
C777  Q_CAP  0.1UF 10V 10% X7S  pkg C0201  page 301 : 1 = P1V8_CPU0_RT2_1A ; 2 = GND
C778  Q_CAP  0.1UF 10V 10% X7S  pkg C0201  page 301 : 1 = P1V8_CPU0_RT2_1A ; 2 = GND
C779  Q_CAP  1UF 4V 20% X6S  pkg 0201  page 301 : 1 = P0V9_CPU0_RT2_2A ; 2 = GND
C780  Q_CAP  0.1UF 10V 10% X7S  pkg C0201  page 301 : 1 = P0V9_CPU0_RT_2D ; 2 = GND
C781  Q_CAP  1UF 4V 20% X6S  pkg 0201  page 301 : 1 = P0V9_CPU0_RT2_2A ; 2 = GND
C782  Q_CAP  0.1UF 10V 10% X7S  pkg C0201  page 301 : 1 = P0V9_CPU0_RT_2D ; 2 = GND
C783  Q_CAP  1UF 4V 20% X6S  pkg 0201  page 301 : 1 = P0V9_CPU0_RT2_2A ; 2 = GND
C784  Q_CAP  0.1UF 10V 10% X7S  pkg C0201  page 301 : 1 = P0V9_CPU0_RT2_2A ; 2 = GND
C785  Q_CAP  0.1UF 10V 10% X7S  pkg C0201  page 301 : 1 = P0V9_CPU0_RT_2D ; 2 = GND
C786  Q_CAP  1UF 4V 20% X6S  pkg 0201  page 301 : 1 = P0V9_CPU0_RT2_2A ; 2 = GND
C787  Q_CAP  1UF 4V 20% X6S  pkg 0201  page 301 : 1 = P0V9_CPU0_RT2_2A_2D ; 2 = GND
C788  Q_CAP  1UF 4V 20% X6S  pkg 0201  page 301 : 1 = P0V9_CPU0_RT2_2A ; 2 = GND
C789  Q_CAP  0.1UF 10V 10% X7S  pkg C0201  page 301 : 1 = P0V9_CPU0_RT_2D ; 2 = GND
C790  Q_CAP  0.1UF 10V 10% X7S  pkg C0201  page 301 : 1 = P0V9_CPU0_RT2_2A ; 2 = GND
C791  Q_CAP  0.1UF 10V 10% X7S  pkg C0201  page 301 : 1 = P0V9_CPU0_RT2_2A_2D ; 2 = GND
C792  Q_CAP  1UF 4V 20% X6S  pkg 0201  page 301 : 1 = P0V9_CPU0_RT2_2A ; 2 = GND
C793  Q_CAP  1UF 4V 20% X6S  pkg 0201  page 301 : 1 = P0V9_CPU0_RT2_2A_2D ; 2 = GND
C794  Q_CAP  0.1UF 10V 10% X7S  pkg C0201  page 301 : 1 = P0V9_CPU0_RT2_2A_2D ; 2 = GND
C795  Q_CAP  100UF 4V 20% X6S  pkg C0805  page 301 : 1 = P0V9_CPU0_RT2_2A ; 2 = GND
C796  Q_CAP  10UF 6.3V 20% X6S  pkg C0402  page 301 : 1 = P0V9_CPU0_RT2_2A ; 2 = GND
C797  Q_CAP  1UF 4V 20% X6S  pkg 0201  page 301 : 1 = P0V9_CPU0_RT2_2A ; 2 = GND
C798  Q_CAP  100UF 4V 20% X6S  pkg C0805  page 301 : 1 = P0V9_CPU0_RT2_2A ; 2 = GND
C799  Q_CAP  22UF 4V 20% X6S  pkg C0402  page 301 : 1 = P0V9_CPU0_RT2_2A ; 2 = GND
C800  Q_CAP  0.1UF 10V 10% X7S  pkg C0201  page 301 : 1 = P0V9_CPU0_RT2_2A ; 2 = GND
C801  Q_CAP  100UF 4V 20% X6S  pkg C0805  page 301 : 1 = P0V9_CPU0_RT_2D ; 2 = GND
C802  Q_CAP  100UF 4V 20% X6S  pkg C0805  page 301 : 1 = P0V9_CPU0_RT2_2A ; 2 = GND
C803  Q_CAP  10UF 6.3V 20% X6S  pkg C0402  page 301 : 1 = P0V9_CPU0_RT2_2A ; 2 = GND
C804  Q_CAP  0.1UF 10V 10% X7S  pkg C0201  page 301 : 1 = P0V9_CPU0_RT2_2A ; 2 = GND
C805  Q_CAP  22UF 4V 20% X6S  pkg C0402  page 301 : 1 = P0V9_CPU0_RT_2D ; 2 = GND
